(kicad_pcb
	(version 20260206)
	(generator "pcbnew")
	(generator_version "10.0")
	(general
		(thickness 1.6)
		(legacy_teardrops no)
	)
	(paper "A4")
	(title_block
		(title "04192023_DAF0TMB3IC0_F0TG_MB_C_brd_V02_OCP.brd")
		(comment 1 "Grand Teton / footprints 633-638 of 8354")
	)
	(layers
		(0 "F.Cu" signal "TOP")
		(4 "In1.Cu" signal "GND")
		(6 "In2.Cu" signal "IN1")
		(8 "In3.Cu" signal "GND1")
		(10 "In4.Cu" signal "IN2")
		(12 "In5.Cu" signal "GND2")
		(14 "In6.Cu" signal "IN3")
		(16 "In7.Cu" signal "GND3")
		(18 "In8.Cu" signal "VCC")
		(20 "In9.Cu" signal "VCC1")
		(22 "In10.Cu" signal "GND4")
		(24 "In11.Cu" signal "IN4")
		(26 "In12.Cu" signal "GND5")
		(28 "In13.Cu" signal "IN5")
		(30 "In14.Cu" signal "GND6")
		(32 "In15.Cu" signal "IN6")
		(34 "In16.Cu" signal "GND7")
		(2 "B.Cu" signal "BOTTOM")
		(9 "F.Adhes" user "F.Adhesive")
		(11 "B.Adhes" user "B.Adhesive")
		(13 "F.Paste" user "Package Geometry/Pastemask Top")
		(15 "B.Paste" user "Package Geometry/Pastemask Bottom")
		(5 "F.SilkS" user "Ref Des/Silkscreen Top")
		(7 "B.SilkS" user "Ref Des/Silkscreen Bottom")
		(1 "F.Mask" user "Board Geometry/Soldermask Top")
		(3 "B.Mask" user "Board Geometry/Soldermask Bottom")
		(17 "Dwgs.User" user "User.Drawings")
		(19 "Cmts.User" user "User.Comments")
		(21 "Eco1.User" user "User.Eco1")
		(23 "Eco2.User" user "User.Eco2")
		(25 "Edge.Cuts" user "Board Geometry/Outline")
		(27 "Margin" user)
		(31 "F.CrtYd" user "Package Geometry/Place Bound Top")
		(29 "B.CrtYd" user "Package Geometry/Place Bound Bottom")
		(35 "F.Fab" user "Ref Des/Assembly Top")
		(33 "B.Fab" user "Ref Des/Assembly Bottom")
	)
	(footprint ""
		(layer "F.Cu")
		(at 301.393098 -25.322276 180)
		(property "Reference" "R5051"
			(at 0 0 180)
			(layer "F.SilkS")
			(hide yes)
			(effects
				(font
					(size 1.27 1.27)
				)
			)
		)
		(property "Value" ""
			(at 0 0 180)
			(layer "F.Fab")
			(effects
				(font
					(size 1.27 1.27)
				)
			)
		)
		(duplicate_pad_numbers_are_jumpers no)
		(fp_line
			(start 0.7874 0.4064)
			(end -0.7874 0.4064)
			(stroke
				(width 0.1524)
				(type default)
			)
			(layer "F.SilkS")
		)
		(fp_line
			(start 0.7874 -0.4064)
			(end 0.7874 0.4064)
			(stroke
				(width 0.1524)
				(type default)
			)
			(layer "F.SilkS")
		)
		(fp_line
			(start -0.7874 0.4064)
			(end -0.7874 -0.4064)
			(stroke
				(width 0.1524)
				(type default)
			)
			(layer "F.SilkS")
		)
		(fp_line
			(start -0.7874 -0.4064)
			(end 0.7874 -0.4064)
			(stroke
				(width 0.1524)
				(type default)
			)
			(layer "F.SilkS")
		)
		(fp_line
			(start 0.67945 0.3048)
			(end 0.120396 0.3048)
			(stroke
				(width 0.1)
				(type default)
			)
			(layer "F.Fab")
		)
		(fp_line
			(start 0.67945 -0.3048)
			(end 0.67945 0.3048)
			(stroke
				(width 0.1)
				(type default)
			)
			(layer "F.Fab")
		)
		(fp_line
			(start 0.12065 -0.2794)
			(end 0.12065 -0.3048)
			(stroke
				(width 0.1)
				(type default)
			)
			(layer "F.Fab")
		)
		(fp_line
			(start 0.12065 -0.3048)
			(end 0.67945 -0.3048)
			(stroke
				(width 0.1)
				(type default)
			)
			(layer "F.Fab")
		)
		(fp_line
			(start 0.120396 0.3048)
			(end 0.120396 0.2794)
			(stroke
				(width 0.1)
				(type default)
			)
			(layer "F.Fab")
		)
		(fp_line
			(start 0.120396 0.2794)
			(end -0.12065 0.2794)
			(stroke
				(width 0.1)
				(type default)
			)
			(layer "F.Fab")
		)
		(fp_line
			(start -0.12065 0.3048)
			(end -0.67945 0.3048)
			(stroke
				(width 0.1)
				(type default)
			)
			(layer "F.Fab")
		)
		(fp_line
			(start -0.12065 0.2794)
			(end -0.12065 0.3048)
			(stroke
				(width 0.1)
				(type default)
			)
			(layer "F.Fab")
		)
		(fp_line
			(start -0.12065 -0.2794)
			(end 0.12065 -0.2794)
			(stroke
				(width 0.1)
				(type default)
			)
			(layer "F.Fab")
		)
		(fp_line
			(start -0.12065 -0.305054)
			(end -0.12065 -0.2794)
			(stroke
				(width 0.1)
				(type default)
			)
			(layer "F.Fab")
		)
		(fp_line
			(start -0.67945 0.3048)
			(end -0.67945 -0.305054)
			(stroke
				(width 0.1)
				(type default)
			)
			(layer "F.Fab")
		)
		(fp_line
			(start -0.67945 -0.305054)
			(end -0.12065 -0.305054)
			(stroke
				(width 0.1)
				(type default)
			)
			(layer "F.Fab")
		)
		(pad "1" smd circle
			(at -0.40005 0 180)
			(size 0 0)
			(layers "F.Cu" "F.Mask" "F.Paste")
			(net "P3V3_RTC_AUX")
		)
		(pad "2" smd circle
			(at 0.40005 0 180)
			(size 0 0)
			(layers "F.Cu" "F.Mask" "F.Paste")
			(net "P1V5_BAT_IN")
		)
	)
	(footprint ""
		(layer "F.Cu")
		(at 146.186652 -78.537562 90)
		(property "Reference" "PC641"
			(at 0 0 90)
			(layer "F.SilkS")
			(hide yes)
			(effects
				(font
					(size 1.27 1.27)
				)
			)
		)
		(property "Value" ""
			(at 0 0 90)
			(layer "F.Fab")
			(effects
				(font
					(size 1.27 1.27)
				)
			)
		)
		(duplicate_pad_numbers_are_jumpers no)
		(fp_line
			(start 0.7874 -0.4064)
			(end 0.7874 0.4064)
			(stroke
				(width 0.1524)
				(type default)
			)
			(layer "F.SilkS")
		)
		(fp_line
			(start -0.7874 -0.4064)
			(end 0.7874 -0.4064)
			(stroke
				(width 0.1524)
				(type default)
			)
			(layer "F.SilkS")
		)
		(fp_line
			(start 0.7874 0.4064)
			(end -0.7874 0.4064)
			(stroke
				(width 0.1524)
				(type default)
			)
			(layer "F.SilkS")
		)
		(fp_line
			(start -0.7874 0.4064)
			(end -0.7874 -0.4064)
			(stroke
				(width 0.1524)
				(type default)
			)
			(layer "F.SilkS")
		)
		(fp_line
			(start -0.12065 -0.305054)
			(end -0.12065 -0.2794)
			(stroke
				(width 0.1)
				(type default)
			)
			(layer "F.Fab")
		)
		(fp_line
			(start -0.67945 -0.305054)
			(end -0.12065 -0.305054)
			(stroke
				(width 0.1)
				(type default)
			)
			(layer "F.Fab")
		)
		(fp_line
			(start 0.67945 -0.3048)
			(end 0.67945 0.3048)
			(stroke
				(width 0.1)
				(type default)
			)
			(layer "F.Fab")
		)
		(fp_line
			(start 0.12065 -0.3048)
			(end 0.67945 -0.3048)
			(stroke
				(width 0.1)
				(type default)
			)
			(layer "F.Fab")
		)
		(fp_line
			(start 0.12065 -0.2794)
			(end 0.12065 -0.3048)
			(stroke
				(width 0.1)
				(type default)
			)
			(layer "F.Fab")
		)
		(fp_line
			(start -0.12065 -0.2794)
			(end 0.12065 -0.2794)
			(stroke
				(width 0.1)
				(type default)
			)
			(layer "F.Fab")
		)
		(fp_line
			(start 0.120396 0.2794)
			(end -0.12065 0.2794)
			(stroke
				(width 0.1)
				(type default)
			)
			(layer "F.Fab")
		)
		(fp_line
			(start -0.12065 0.2794)
			(end -0.12065 0.3048)
			(stroke
				(width 0.1)
				(type default)
			)
			(layer "F.Fab")
		)
		(fp_line
			(start 0.67945 0.3048)
			(end 0.120396 0.3048)
			(stroke
				(width 0.1)
				(type default)
			)
			(layer "F.Fab")
		)
		(fp_line
			(start 0.120396 0.3048)
			(end 0.120396 0.2794)
			(stroke
				(width 0.1)
				(type default)
			)
			(layer "F.Fab")
		)
		(fp_line
			(start -0.12065 0.3048)
			(end -0.67945 0.3048)
			(stroke
				(width 0.1)
				(type default)
			)
			(layer "F.Fab")
		)
		(fp_line
			(start -0.67945 0.3048)
			(end -0.67945 -0.305054)
			(stroke
				(width 0.1)
				(type default)
			)
			(layer "F.Fab")
		)
		(pad "1" smd circle
			(at -0.40005 0 90)
			(size 0 0)
			(layers "F.Cu" "F.Mask" "F.Paste")
			(net "SW_P1V8_AUX_BT_R")
		)
		(pad "2" smd circle
			(at 0.40005 0 90)
			(size 0 0)
			(layers "F.Cu" "F.Mask" "F.Paste")
			(net "SW_P1V8_AUX_PH")
		)
	)
	(footprint ""
		(layer "F.Cu")
		(at 191.295782 -28.267152)
		(property "Reference" "PC2237"
			(at 0 0 0)
			(layer "F.SilkS")
			(hide yes)
			(effects
				(font
					(size 1.27 1.27)
				)
			)
		)
		(property "Value" ""
			(at 0 0 0)
			(layer "F.Fab")
			(effects
				(font
					(size 1.27 1.27)
				)
			)
		)
		(duplicate_pad_numbers_are_jumpers no)
		(fp_line
			(start -0.7874 -0.4064)
			(end 0.7874 -0.4064)
			(stroke
				(width 0.1524)
				(type default)
			)
			(layer "F.SilkS")
		)
		(fp_line
			(start -0.7874 0.4064)
			(end -0.7874 -0.4064)
			(stroke
				(width 0.1524)
				(type default)
			)
			(layer "F.SilkS")
		)
		(fp_line
			(start 0.7874 -0.4064)
			(end 0.7874 0.4064)
			(stroke
				(width 0.1524)
				(type default)
			)
			(layer "F.SilkS")
		)
		(fp_line
			(start 0.7874 0.4064)
			(end -0.7874 0.4064)
			(stroke
				(width 0.1524)
				(type default)
			)
			(layer "F.SilkS")
		)
		(fp_line
			(start -0.67945 -0.305054)
			(end -0.12065 -0.305054)
			(stroke
				(width 0.1)
				(type default)
			)
			(layer "F.Fab")
		)
		(fp_line
			(start -0.67945 0.3048)
			(end -0.67945 -0.305054)
			(stroke
				(width 0.1)
				(type default)
			)
			(layer "F.Fab")
		)
		(fp_line
			(start -0.12065 -0.305054)
			(end -0.12065 -0.2794)
			(stroke
				(width 0.1)
				(type default)
			)
			(layer "F.Fab")
		)
		(fp_line
			(start -0.12065 -0.2794)
			(end 0.12065 -0.2794)
			(stroke
				(width 0.1)
				(type default)
			)
			(layer "F.Fab")
		)
		(fp_line
			(start -0.12065 0.2794)
			(end -0.12065 0.3048)
			(stroke
				(width 0.1)
				(type default)
			)
			(layer "F.Fab")
		)
		(fp_line
			(start -0.12065 0.3048)
			(end -0.67945 0.3048)
			(stroke
				(width 0.1)
				(type default)
			)
			(layer "F.Fab")
		)
		(fp_line
			(start 0.120396 0.2794)
			(end -0.12065 0.2794)
			(stroke
				(width 0.1)
				(type default)
			)
			(layer "F.Fab")
		)
		(fp_line
			(start 0.120396 0.3048)
			(end 0.120396 0.2794)
			(stroke
				(width 0.1)
				(type default)
			)
			(layer "F.Fab")
		)
		(fp_line
			(start 0.12065 -0.3048)
			(end 0.67945 -0.3048)
			(stroke
				(width 0.1)
				(type default)
			)
			(layer "F.Fab")
		)
		(fp_line
			(start 0.12065 -0.2794)
			(end 0.12065 -0.3048)
			(stroke
				(width 0.1)
				(type default)
			)
			(layer "F.Fab")
		)
		(fp_line
			(start 0.67945 -0.3048)
			(end 0.67945 0.3048)
			(stroke
				(width 0.1)
				(type default)
			)
			(layer "F.Fab")
		)
		(fp_line
			(start 0.67945 0.3048)
			(end 0.120396 0.3048)
			(stroke
				(width 0.1)
				(type default)
			)
			(layer "F.Fab")
		)
		(pad "1" smd circle
			(at -0.40005 0)
			(size 0 0)
			(layers "F.Cu" "F.Mask" "F.Paste")
			(net "P12V_SCM_GATE")
		)
		(pad "2" smd circle
			(at 0.40005 0)
			(size 0 0)
			(layers "F.Cu" "F.Mask" "F.Paste")
			(net "GND")
		)
	)
	(footprint ""
		(layer "F.Cu")
		(at 130.946906 -21.372068 90)
		(property "Reference" "R3254"
			(at 0 0 90)
			(layer "F.SilkS")
			(hide yes)
			(effects
				(font
					(size 1.27 1.27)
				)
			)
		)
		(property "Value" ""
			(at 0 0 90)
			(layer "F.Fab")
			(effects
				(font
					(size 1.27 1.27)
				)
			)
		)
		(duplicate_pad_numbers_are_jumpers no)
		(fp_line
			(start 0.7874 -0.4064)
			(end 0.7874 0.4064)
			(stroke
				(width 0.1524)
				(type default)
			)
			(layer "F.SilkS")
		)
		(fp_line
			(start -0.7874 -0.4064)
			(end 0.7874 -0.4064)
			(stroke
				(width 0.1524)
				(type default)
			)
			(layer "F.SilkS")
		)
		(fp_line
			(start 0.7874 0.4064)
			(end -0.7874 0.4064)
			(stroke
				(width 0.1524)
				(type default)
			)
			(layer "F.SilkS")
		)
		(fp_line
			(start -0.7874 0.4064)
			(end -0.7874 -0.4064)
			(stroke
				(width 0.1524)
				(type default)
			)
			(layer "F.SilkS")
		)
		(fp_line
			(start -0.12065 -0.305054)
			(end -0.12065 -0.2794)
			(stroke
				(width 0.1)
				(type default)
			)
			(layer "F.Fab")
		)
		(fp_line
			(start -0.67945 -0.305054)
			(end -0.12065 -0.305054)
			(stroke
				(width 0.1)
				(type default)
			)
			(layer "F.Fab")
		)
		(fp_line
			(start 0.67945 -0.3048)
			(end 0.67945 0.3048)
			(stroke
				(width 0.1)
				(type default)
			)
			(layer "F.Fab")
		)
		(fp_line
			(start 0.12065 -0.3048)
			(end 0.67945 -0.3048)
			(stroke
				(width 0.1)
				(type default)
			)
			(layer "F.Fab")
		)
		(fp_line
			(start 0.12065 -0.2794)
			(end 0.12065 -0.3048)
			(stroke
				(width 0.1)
				(type default)
			)
			(layer "F.Fab")
		)
		(fp_line
			(start -0.12065 -0.2794)
			(end 0.12065 -0.2794)
			(stroke
				(width 0.1)
				(type default)
			)
			(layer "F.Fab")
		)
		(fp_line
			(start 0.120396 0.2794)
			(end -0.12065 0.2794)
			(stroke
				(width 0.1)
				(type default)
			)
			(layer "F.Fab")
		)
		(fp_line
			(start -0.12065 0.2794)
			(end -0.12065 0.3048)
			(stroke
				(width 0.1)
				(type default)
			)
			(layer "F.Fab")
		)
		(fp_line
			(start 0.67945 0.3048)
			(end 0.120396 0.3048)
			(stroke
				(width 0.1)
				(type default)
			)
			(layer "F.Fab")
		)
		(fp_line
			(start 0.120396 0.3048)
			(end 0.120396 0.2794)
			(stroke
				(width 0.1)
				(type default)
			)
			(layer "F.Fab")
		)
		(fp_line
			(start -0.12065 0.3048)
			(end -0.67945 0.3048)
			(stroke
				(width 0.1)
				(type default)
			)
			(layer "F.Fab")
		)
		(fp_line
			(start -0.67945 0.3048)
			(end -0.67945 -0.305054)
			(stroke
				(width 0.1)
				(type default)
			)
			(layer "F.Fab")
		)
		(pad "1" smd circle
			(at -0.40005 0 90)
			(size 0 0)
			(layers "F.Cu" "F.Mask" "F.Paste")
			(net "TP_PCIE_TXP<3>")
		)
		(pad "2" smd circle
			(at 0.40005 0 90)
			(size 0 0)
			(layers "F.Cu" "F.Mask" "F.Paste")
			(net "LED_HDD_ACTIVITY_B_N")
		)
	)
	(footprint ""
		(layer "F.Cu")
		(at 394.164058 -177.04562 90)
		(property "Reference" "PC585_1"
			(at 0 0 90)
			(layer "F.SilkS")
			(hide yes)
			(effects
				(font
					(size 1.27 1.27)
				)
			)
		)
		(property "Value" ""
			(at 0 0 90)
			(layer "F.Fab")
			(effects
				(font
					(size 1.27 1.27)
				)
			)
		)
		(duplicate_pad_numbers_are_jumpers no)
		(fp_line
			(start 0.7874 -0.4064)
			(end 0.7874 0.4064)
			(stroke
				(width 0.1524)
				(type default)
			)
			(layer "F.SilkS")
		)
		(fp_line
			(start -0.7874 -0.4064)
			(end 0.7874 -0.4064)
			(stroke
				(width 0.1524)
				(type default)
			)
			(layer "F.SilkS")
		)
		(fp_line
			(start 0.7874 0.4064)
			(end -0.7874 0.4064)
			(stroke
				(width 0.1524)
				(type default)
			)
			(layer "F.SilkS")
		)
		(fp_line
			(start -0.7874 0.4064)
			(end -0.7874 -0.4064)
			(stroke
				(width 0.1524)
				(type default)
			)
			(layer "F.SilkS")
		)
		(fp_line
			(start -0.12065 -0.305054)
			(end -0.12065 -0.2794)
			(stroke
				(width 0.1)
				(type default)
			)
			(layer "F.Fab")
		)
		(fp_line
			(start -0.67945 -0.305054)
			(end -0.12065 -0.305054)
			(stroke
				(width 0.1)
				(type default)
			)
			(layer "F.Fab")
		)
		(fp_line
			(start 0.67945 -0.3048)
			(end 0.67945 0.3048)
			(stroke
				(width 0.1)
				(type default)
			)
			(layer "F.Fab")
		)
		(fp_line
			(start 0.12065 -0.3048)
			(end 0.67945 -0.3048)
			(stroke
				(width 0.1)
				(type default)
			)
			(layer "F.Fab")
		)
		(fp_line
			(start 0.12065 -0.2794)
			(end 0.12065 -0.3048)
			(stroke
				(width 0.1)
				(type default)
			)
			(layer "F.Fab")
		)
		(fp_line
			(start -0.12065 -0.2794)
			(end 0.12065 -0.2794)
			(stroke
				(width 0.1)
				(type default)
			)
			(layer "F.Fab")
		)
		(fp_line
			(start 0.120396 0.2794)
			(end -0.12065 0.2794)
			(stroke
				(width 0.1)
				(type default)
			)
			(layer "F.Fab")
		)
		(fp_line
			(start -0.12065 0.2794)
			(end -0.12065 0.3048)
			(stroke
				(width 0.1)
				(type default)
			)
			(layer "F.Fab")
		)
		(fp_line
			(start 0.67945 0.3048)
			(end 0.120396 0.3048)
			(stroke
				(width 0.1)
				(type default)
			)
			(layer "F.Fab")
		)
		(fp_line
			(start 0.120396 0.3048)
			(end 0.120396 0.2794)
			(stroke
				(width 0.1)
				(type default)
			)
			(layer "F.Fab")
		)
		(fp_line
			(start -0.12065 0.3048)
			(end -0.67945 0.3048)
			(stroke
				(width 0.1)
				(type default)
			)
			(layer "F.Fab")
		)
		(fp_line
			(start -0.67945 0.3048)
			(end -0.67945 -0.305054)
			(stroke
				(width 0.1)
				(type default)
			)
			(layer "F.Fab")
		)
		(pad "1" smd circle
			(at -0.40005 0 90)
			(size 0 0)
			(layers "F.Cu" "F.Mask" "F.Paste")
			(net "SW_P12V_AUX_PVDDCR_SOC_P0_FLT")
		)
		(pad "2" smd circle
			(at 0.40005 0 90)
			(size 0 0)
			(layers "F.Cu" "F.Mask" "F.Paste")
			(net "GND")
		)
	)
	(footprint ""
		(layer "F.Cu")
		(at 357.958644 -378.95403 -90)
		(property "Reference" "C938"
			(at 0 0 270)
			(layer "F.SilkS")
			(hide yes)
			(effects
				(font
					(size 1.27 1.27)
				)
			)
		)
		(property "Value" ""
			(at 0 0 270)
			(layer "F.Fab")
			(effects
				(font
					(size 1.27 1.27)
				)
			)
		)
		(duplicate_pad_numbers_are_jumpers no)
		(fp_line
			(start -0.299974 0.150114)
			(end -0.299974 -0.150114)
			(stroke
				(width 0.1)
				(type default)
			)
			(layer "F.Fab")
		)
		(fp_line
			(start 0.299974 0.150114)
			(end -0.299974 0.150114)
			(stroke
				(width 0.1)
				(type default)
			)
			(layer "F.Fab")
		)
		(fp_line
			(start -0.299974 -0.150114)
			(end 0.299974 -0.150114)
			(stroke
				(width 0.1)
				(type default)
			)
			(layer "F.Fab")
		)
		(fp_line
			(start 0.299974 -0.150114)
			(end 0.299974 0.150114)
			(stroke
				(width 0.1)
				(type default)
			)
			(layer "F.Fab")
		)
		(pad "1" smd rect
			(at -0.2667 0 270)
			(size 0.3048 0.381)
			(layers "F.Cu" "F.Mask" "F.Paste")
			(net "P5E_CPU0_P1_TX_C_DN<13>")
		)
		(pad "2" smd rect
			(at 0.2667 0 270)
			(size 0.3048 0.381)
			(layers "F.Cu" "F.Mask" "F.Paste")
			(net "P5E_CPU0_P1_TX_DN<13>")
		)
	)
)
